G04 ================== begin FILE IDENTIFICATION RECORD ==================*
G04 Layout Name:  DA0T6MTH8C0_t6m_tray_bp_c_brd_103112_274.brd*
G04 Film Name:    pmb*
G04 File Format:  Gerber RS274X*
G04 File Origin:  Cadence Allegro 16.3-S048*
G04 Origin Date:  Tue Nov 26 11:26:41 2013*
G04 *
G04 Layer:  VIA CLASS/PASTEMASK_BOTTOM*
G04 Layer:  PIN/PASTEMASK_BOTTOM*
G04 Layer:  PACKAGE GEOMETRY/PASTEMASK_BOTTOM*
G04 Layer:  MANUFACTURING/PHOTOPLOT_OUTLINE*
G04 Layer:  DRAWING FORMAT/TITLE_BLOCK*
G04 Layer:  DRAWING FORMAT/TITLE_DATA_PMB*
G04 *
G04 Offset:    (0.00 0.00)*
G04 Mirror:    No*
G04 Mode:      Positive*
G04 Rotation:  0*
G04 FullContactRelief:  No*
G04 UndefLineWidth:     6.00*
G04 ================== end FILE IDENTIFICATION RECORD ====================*
%FSLAX25Y25*MOIN*%
%IR0*IPPOS*OFA0.00000B0.00000*MIA0B0*SFA1.00000B1.00000*%
%ADD16C,.04*%
%ADD17C,.051*%
%ADD14C,.026*%
%ADD15C,.054*%
%ADD12C,.063*%
%ADD10C,.066*%
%ADD19R,.051X.051*%
%ADD13R,.063X.063*%
%ADD11R,.066X.066*%
%ADD20R,.103X.426*%
%ADD18C,.12*%
%ADD21C,.006*%
G75*
%LPD*%
G75*
G54D10*
X9088Y80158D03*
Y91958D03*
X109288Y92458D03*
Y103958D03*
G54D20*
X1676417Y102756D03*
G54D11*
X19088Y80158D03*
Y91958D03*
X119288Y92458D03*
Y103958D03*
G54D21*
G01X457212Y-338900D02*
Y-343900D01*
G01X455755Y-338900D02*
X458669D01*
G01X463579Y-343900D02*
X461045D01*
Y-338900D01*
X463579D01*
G01X462565Y-341317D02*
X461045D01*
G01X466145Y-338900D02*
Y-343900D01*
X468679D01*
G01X472512Y-344067D02*
X472385Y-343983D01*
Y-343817D01*
X472512Y-343733D01*
X472639Y-343817D01*
Y-343983D01*
X472512Y-344067D01*
G01Y-341817D02*
X472385Y-341733D01*
Y-341567D01*
X472512Y-341483D01*
X472639Y-341567D01*
Y-341733D01*
X472512Y-341817D01*
G01X477295Y-345567D02*
X476662Y-344733D01*
X476345Y-343900D01*
Y-340567D01*
X476662Y-339733D01*
X477295Y-338900D01*
G01X482712D02*
X482205Y-339067D01*
X481825Y-339483D01*
X481572Y-339983D01*
X481382Y-340650D01*
X481319Y-341400D01*
X481382Y-342150D01*
X481572Y-342817D01*
X481825Y-343317D01*
X482205Y-343733D01*
X482712Y-343900D01*
X483219Y-343733D01*
X483599Y-343317D01*
X483852Y-342817D01*
X484042Y-342150D01*
X484105Y-341400D01*
X484042Y-340650D01*
X483852Y-339983D01*
X483599Y-339483D01*
X483219Y-339067D01*
X482712Y-338900D01*
G01X486419Y-342900D02*
X486799Y-343483D01*
X487305Y-343817D01*
X487875Y-343900D01*
X488382Y-343817D01*
X488889Y-343400D01*
X489205Y-342900D01*
X489269Y-342400D01*
X489142Y-341817D01*
X488699Y-341400D01*
X488255Y-341233D01*
X487685D01*
G01X488255D02*
X488635Y-340983D01*
X488952Y-340567D01*
X489079Y-340067D01*
X488952Y-339567D01*
X488635Y-339150D01*
X488065Y-338900D01*
X487495Y-338983D01*
X486925Y-339317D01*
G01X493229Y-345567D02*
X493862Y-344733D01*
X494179Y-343900D01*
Y-340567D01*
X493862Y-339733D01*
X493229Y-338900D01*
G01X496619Y-342900D02*
X496999Y-343483D01*
X497505Y-343817D01*
X498075Y-343900D01*
X498582Y-343817D01*
X499089Y-343400D01*
X499405Y-342900D01*
X499469Y-342400D01*
X499342Y-341817D01*
X498899Y-341400D01*
X498455Y-341233D01*
X497885D01*
G01X498455D02*
X498835Y-340983D01*
X499152Y-340567D01*
X499279Y-340067D01*
X499152Y-339567D01*
X498835Y-339150D01*
X498265Y-338900D01*
X497695Y-338983D01*
X497125Y-339317D01*
G01X501909Y-339733D02*
X502289Y-339233D01*
X502732Y-338983D01*
X503239Y-338900D01*
X503872Y-339067D01*
X504315Y-339483D01*
X504442Y-339983D01*
X504379Y-340483D01*
X504125Y-340900D01*
X502859Y-341733D01*
X502289Y-342317D01*
X501909Y-343150D01*
X501782Y-343900D01*
X504442D01*
G01X508085D02*
X508212Y-342817D01*
X508402Y-341900D01*
X508655Y-341067D01*
X508972Y-340150D01*
X509479Y-338900D01*
X506945D01*
G01X512489Y-342233D02*
X514135D01*
G01X517209Y-339733D02*
X517589Y-339233D01*
X518032Y-338983D01*
X518539Y-338900D01*
X519172Y-339067D01*
X519615Y-339483D01*
X519742Y-339983D01*
X519679Y-340483D01*
X519425Y-340900D01*
X518159Y-341733D01*
X517589Y-342317D01*
X517209Y-343150D01*
X517082Y-343900D01*
X519742D01*
G01X522119Y-342900D02*
X522499Y-343483D01*
X523005Y-343817D01*
X523575Y-343900D01*
X524082Y-343817D01*
X524589Y-343400D01*
X524905Y-342900D01*
X524969Y-342400D01*
X524842Y-341817D01*
X524399Y-341400D01*
X523955Y-341233D01*
X523385D01*
G01X523955D02*
X524335Y-340983D01*
X524652Y-340567D01*
X524779Y-340067D01*
X524652Y-339567D01*
X524335Y-339150D01*
X523765Y-338900D01*
X523195Y-338983D01*
X522625Y-339317D01*
G01X529372Y-343900D02*
Y-338900D01*
X527029Y-342483D01*
X530195D01*
G01X532319Y-343150D02*
X532699Y-343567D01*
X533142Y-343817D01*
X533712Y-343900D01*
X534282Y-343733D01*
X534725Y-343400D01*
X535042Y-342817D01*
X535105Y-342150D01*
X534979Y-341483D01*
X534662Y-341067D01*
X534219Y-340733D01*
X533775Y-340650D01*
X533332Y-340733D01*
X532762Y-341067D01*
X532952Y-338900D01*
X534662D01*
G01X542709Y-343900D02*
Y-338900D01*
X545115D01*
G01X544229Y-341317D02*
X542709D01*
G01X547429Y-343900D02*
X549012Y-338900D01*
X550595Y-343900D01*
G01X550025Y-342150D02*
X547999D01*
G01X552782Y-343900D02*
X555442Y-338900D01*
G01X552782D02*
X555442Y-343900D01*
G01X559212Y-344067D02*
X559085Y-343983D01*
Y-343817D01*
X559212Y-343733D01*
X559339Y-343817D01*
Y-343983D01*
X559212Y-344067D01*
G01Y-341817D02*
X559085Y-341733D01*
Y-341567D01*
X559212Y-341483D01*
X559339Y-341567D01*
Y-341733D01*
X559212Y-341817D01*
G01X563995Y-345567D02*
X563362Y-344733D01*
X563045Y-343900D01*
Y-340567D01*
X563362Y-339733D01*
X563995Y-338900D01*
G01X569412D02*
X568905Y-339067D01*
X568525Y-339483D01*
X568272Y-339983D01*
X568082Y-340650D01*
X568019Y-341400D01*
X568082Y-342150D01*
X568272Y-342817D01*
X568525Y-343317D01*
X568905Y-343733D01*
X569412Y-343900D01*
X569919Y-343733D01*
X570299Y-343317D01*
X570552Y-342817D01*
X570742Y-342150D01*
X570805Y-341400D01*
X570742Y-340650D01*
X570552Y-339983D01*
X570299Y-339483D01*
X569919Y-339067D01*
X569412Y-338900D01*
G01X573119Y-342900D02*
X573499Y-343483D01*
X574005Y-343817D01*
X574575Y-343900D01*
X575082Y-343817D01*
X575589Y-343400D01*
X575905Y-342900D01*
X575969Y-342400D01*
X575842Y-341817D01*
X575399Y-341400D01*
X574955Y-341233D01*
X574385D01*
G01X574955D02*
X575335Y-340983D01*
X575652Y-340567D01*
X575779Y-340067D01*
X575652Y-339567D01*
X575335Y-339150D01*
X574765Y-338900D01*
X574195Y-338983D01*
X573625Y-339317D01*
G01X579929Y-345567D02*
X580562Y-344733D01*
X580879Y-343900D01*
Y-340567D01*
X580562Y-339733D01*
X579929Y-338900D01*
G01X583319Y-342900D02*
X583699Y-343483D01*
X584205Y-343817D01*
X584775Y-343900D01*
X585282Y-343817D01*
X585789Y-343400D01*
X586105Y-342900D01*
X586169Y-342400D01*
X586042Y-341817D01*
X585599Y-341400D01*
X585155Y-341233D01*
X584585D01*
G01X585155D02*
X585535Y-340983D01*
X585852Y-340567D01*
X585979Y-340067D01*
X585852Y-339567D01*
X585535Y-339150D01*
X584965Y-338900D01*
X584395Y-338983D01*
X583825Y-339317D01*
G01X588735Y-343317D02*
X589179Y-343733D01*
X589685Y-343900D01*
X590192Y-343733D01*
X590635Y-343233D01*
X590952Y-342483D01*
X591079Y-341733D01*
Y-340817D01*
X590952Y-340067D01*
X590635Y-339400D01*
X590255Y-339067D01*
X589812Y-338900D01*
X589305Y-339067D01*
X588925Y-339400D01*
X588672Y-339900D01*
X588545Y-340567D01*
X588672Y-341150D01*
X588989Y-341733D01*
X589369Y-342067D01*
X589812Y-342150D01*
X590319Y-341983D01*
X590699Y-341567D01*
X591079Y-340817D01*
G01X594785Y-343900D02*
X594912Y-342817D01*
X595102Y-341900D01*
X595355Y-341067D01*
X595672Y-340150D01*
X596179Y-338900D01*
X593645D01*
G01X599189Y-342233D02*
X600835D01*
G01X603719Y-342900D02*
X604099Y-343483D01*
X604605Y-343817D01*
X605175Y-343900D01*
X605682Y-343817D01*
X606189Y-343400D01*
X606505Y-342900D01*
X606569Y-342400D01*
X606442Y-341817D01*
X605999Y-341400D01*
X605555Y-341233D01*
X604985D01*
G01X605555D02*
X605935Y-340983D01*
X606252Y-340567D01*
X606379Y-340067D01*
X606252Y-339567D01*
X605935Y-339150D01*
X605365Y-338900D01*
X604795Y-338983D01*
X604225Y-339317D01*
G01X609009Y-341817D02*
X609452Y-341233D01*
X609832Y-340900D01*
X610339Y-340733D01*
X610782Y-340900D01*
X611099Y-341233D01*
X611352Y-341733D01*
X611415Y-342317D01*
X611352Y-342817D01*
X611099Y-343317D01*
X610719Y-343733D01*
X610275Y-343900D01*
X609769Y-343733D01*
X609325Y-343233D01*
X609072Y-342483D01*
X609009Y-341650D01*
X609135Y-340567D01*
X609325Y-339983D01*
X609642Y-339400D01*
X610085Y-338983D01*
X610529Y-338900D01*
X610972Y-339067D01*
X611289Y-339483D01*
G01X615312Y-343900D02*
Y-338900D01*
X614552Y-339900D01*
G01Y-343900D02*
X616072D01*
G01X621172D02*
Y-338900D01*
X618829Y-342483D01*
X621995D01*
G01X445212Y-273900D02*
Y-348900D01*
X945212D01*
Y-273900D01*
X445212D01*
G01X640212D02*
Y-348900D01*
G01Y-323900D02*
X743212D01*
Y-298900D01*
G01X640212D02*
X743212D01*
G01Y-273900D02*
Y-348900D01*
G01X745212Y-273900D02*
Y-348900D01*
G01X750719Y-333900D02*
Y-328900D01*
X751985D01*
X752492Y-329150D01*
X752872Y-329483D01*
X753189Y-329983D01*
X753442Y-330567D01*
X753505Y-331400D01*
X753442Y-332233D01*
X753189Y-332817D01*
X752872Y-333317D01*
X752492Y-333650D01*
X751985Y-333900D01*
X750719D01*
G01X755629D02*
X757212Y-328900D01*
X758795Y-333900D01*
G01X758225Y-332150D02*
X756199D01*
G01X762312Y-328900D02*
Y-333900D01*
G01X760855Y-328900D02*
X763769D01*
G01X768679Y-333900D02*
X766145D01*
Y-328900D01*
X768679D01*
G01X767665Y-331317D02*
X766145D01*
G01X772512Y-334067D02*
X772385Y-333983D01*
Y-333817D01*
X772512Y-333733D01*
X772639Y-333817D01*
Y-333983D01*
X772512Y-334067D01*
G01Y-331817D02*
X772385Y-331733D01*
Y-331567D01*
X772512Y-331483D01*
X772639Y-331567D01*
Y-331733D01*
X772512Y-331817D01*
G01X745212Y-323900D02*
X945212D01*
G01X750845Y-308900D02*
Y-303900D01*
X752365D01*
X752872Y-304150D01*
X753252Y-304733D01*
X753379Y-305400D01*
X753252Y-306067D01*
X752935Y-306567D01*
X752365Y-306817D01*
X750845D01*
G01X756072Y-309067D02*
X758352Y-303900D01*
G01X760855Y-308900D02*
Y-303900D01*
X763769Y-308900D01*
Y-303900D01*
G01X767412Y-309067D02*
X767285Y-308983D01*
Y-308817D01*
X767412Y-308733D01*
X767539Y-308817D01*
Y-308983D01*
X767412Y-309067D01*
G01Y-306817D02*
X767285Y-306733D01*
Y-306567D01*
X767412Y-306483D01*
X767539Y-306567D01*
Y-306733D01*
X767412Y-306817D01*
G01X745212Y-298900D02*
X945212D01*
G01X750845Y-283900D02*
Y-278900D01*
X752365D01*
X752872Y-279150D01*
X753252Y-279733D01*
X753379Y-280400D01*
X753252Y-281067D01*
X752935Y-281567D01*
X752365Y-281817D01*
X750845D01*
G01X755945Y-283900D02*
Y-278900D01*
X757529D01*
X758035Y-279150D01*
X758352Y-279483D01*
X758479Y-280150D01*
X758352Y-280817D01*
X757972Y-281233D01*
X757529Y-281483D01*
X755945D01*
G01X757529D02*
X758479Y-283900D01*
G01X762312D02*
X761805Y-283817D01*
X761362Y-283483D01*
X760982Y-282983D01*
X760729Y-282400D01*
X760602Y-281733D01*
Y-281067D01*
X760729Y-280400D01*
X760982Y-279817D01*
X761362Y-279317D01*
X761805Y-278983D01*
X762312Y-278900D01*
X762819Y-278983D01*
X763262Y-279317D01*
X763642Y-279817D01*
X763895Y-280400D01*
X764022Y-281067D01*
Y-281733D01*
X763895Y-282400D01*
X763642Y-282983D01*
X763262Y-283483D01*
X762819Y-283817D01*
X762312Y-283900D01*
G01X766145Y-282900D02*
X766462Y-283400D01*
X766842Y-283733D01*
X767285Y-283900D01*
X767792Y-283733D01*
X768172Y-283400D01*
X768552Y-282900D01*
X768679Y-282233D01*
Y-278900D01*
G01X773779Y-283900D02*
X771245D01*
Y-278900D01*
X773779D01*
G01X772765Y-281317D02*
X771245D01*
G01X779005Y-279317D02*
X778625Y-279067D01*
X778182Y-278900D01*
X777675D01*
X777105Y-279150D01*
X776662Y-279567D01*
X776345Y-280067D01*
X776092Y-280900D01*
X776029Y-281650D01*
X776155Y-282400D01*
X776345Y-282900D01*
X776725Y-283400D01*
X777169Y-283733D01*
X777612Y-283900D01*
X778055D01*
X778499Y-283733D01*
X778879Y-283483D01*
X779195Y-283150D01*
G01X782712Y-278900D02*
Y-283900D01*
G01X781255Y-278900D02*
X784169D01*
G01X787812Y-284067D02*
X787685Y-283983D01*
Y-283817D01*
X787812Y-283733D01*
X787939Y-283817D01*
Y-283983D01*
X787812Y-284067D01*
G01Y-281817D02*
X787685Y-281733D01*
Y-281567D01*
X787812Y-281483D01*
X787939Y-281567D01*
Y-281733D01*
X787812Y-281817D01*
G01X860212Y-323900D02*
Y-348900D01*
G01X865845Y-333900D02*
Y-328900D01*
X867429D01*
X867935Y-329150D01*
X868252Y-329483D01*
X868379Y-330150D01*
X868252Y-330817D01*
X867872Y-331233D01*
X867429Y-331483D01*
X865845D01*
G01X867429D02*
X868379Y-333900D01*
G01X873479D02*
X870945D01*
Y-328900D01*
X873479D01*
G01X872465Y-331317D02*
X870945D01*
G01X875729Y-328900D02*
X877312Y-333900D01*
X878895Y-328900D01*
G01X882412Y-334067D02*
X882285Y-333983D01*
Y-333817D01*
X882412Y-333733D01*
X882539Y-333817D01*
Y-333983D01*
X882412Y-334067D01*
G01Y-331817D02*
X882285Y-331733D01*
Y-331567D01*
X882412Y-331483D01*
X882539Y-331567D01*
Y-331733D01*
X882412Y-331817D01*
G01X909212Y-323900D02*
Y-348900D01*
G01X-471400Y-391900D02*
Y1528800D01*
X2244200D01*
Y-391900D01*
X-471400D01*
G01X455917Y-335560D02*
X456544Y-336085D01*
X457249Y-336400D01*
X457875D01*
X458502Y-336085D01*
X458972Y-335560D01*
X459207Y-334825D01*
X459050Y-334090D01*
X458659Y-333460D01*
X457954Y-333040D01*
X457014Y-332830D01*
X456465Y-332410D01*
X456230Y-331675D01*
X456387Y-330940D01*
X456779Y-330415D01*
X457327Y-330100D01*
X457875D01*
X458424Y-330310D01*
X458894Y-330835D01*
G01X462217Y-336400D02*
Y-330100D01*
G01X465507D02*
Y-336400D01*
G01Y-333250D02*
X462217D01*
G01X469222Y-330100D02*
X471102D01*
G01X470162D02*
Y-336400D01*
G01X469222D02*
X471102D01*
G01X478029D02*
X474895D01*
Y-330100D01*
X478029D01*
G01X476775Y-333145D02*
X474895D01*
G01X480960Y-336400D02*
Y-330100D01*
X484564Y-336400D01*
Y-330100D01*
G01X488905Y-337555D02*
X489219Y-336190D01*
G01X495362Y-330100D02*
Y-336400D01*
G01X493560Y-330100D02*
X497164D01*
G01X499704Y-336400D02*
X501662Y-330100D01*
X503620Y-336400D01*
G01X502915Y-334195D02*
X500409D01*
G01X507022Y-330100D02*
X508902D01*
G01X507962D02*
Y-336400D01*
G01X507022D02*
X508902D01*
G01X511912Y-330100D02*
X513009Y-336400D01*
X514262Y-330100D01*
X515515Y-336400D01*
X516612Y-330100D01*
G01X518604Y-336400D02*
X520562Y-330100D01*
X522520Y-336400D01*
G01X521815Y-334195D02*
X519309D01*
G01X525060Y-336400D02*
Y-330100D01*
X528664Y-336400D01*
Y-330100D01*
G01X537895Y-336400D02*
Y-330100D01*
X539854D01*
X540480Y-330415D01*
X540872Y-330835D01*
X541029Y-331675D01*
X540872Y-332515D01*
X540402Y-333040D01*
X539854Y-333355D01*
X537895D01*
G01X539854D02*
X541029Y-336400D01*
G01X545762Y-336610D02*
X545605Y-336505D01*
Y-336295D01*
X545762Y-336190D01*
X545919Y-336295D01*
Y-336505D01*
X545762Y-336610D01*
G01X552062Y-336400D02*
X551435Y-336295D01*
X550887Y-335875D01*
X550417Y-335245D01*
X550104Y-334510D01*
X549947Y-333670D01*
Y-332830D01*
X550104Y-331990D01*
X550417Y-331255D01*
X550887Y-330625D01*
X551435Y-330205D01*
X552062Y-330100D01*
X552689Y-330205D01*
X553237Y-330625D01*
X553707Y-331255D01*
X554020Y-331990D01*
X554177Y-332830D01*
Y-333670D01*
X554020Y-334510D01*
X553707Y-335245D01*
X553237Y-335875D01*
X552689Y-336295D01*
X552062Y-336400D01*
G01X558362Y-336610D02*
X558205Y-336505D01*
Y-336295D01*
X558362Y-336190D01*
X558519Y-336295D01*
Y-336505D01*
X558362Y-336610D01*
G01X566385Y-330625D02*
X565915Y-330310D01*
X565367Y-330100D01*
X564740D01*
X564035Y-330415D01*
X563487Y-330940D01*
X563095Y-331570D01*
X562782Y-332620D01*
X562704Y-333565D01*
X562860Y-334510D01*
X563095Y-335140D01*
X563565Y-335770D01*
X564114Y-336190D01*
X564662Y-336400D01*
X565210D01*
X565759Y-336190D01*
X566229Y-335875D01*
X566620Y-335455D01*
G01X570962Y-336610D02*
X570805Y-336505D01*
Y-336295D01*
X570962Y-336190D01*
X571119Y-336295D01*
Y-336505D01*
X570962Y-336610D01*
G01X455839Y-326400D02*
Y-320100D01*
G01X458815D02*
X455839Y-323985D01*
G01X459285Y-326400D02*
X457170Y-322200D01*
G01X462139Y-320100D02*
Y-324615D01*
X462452Y-325560D01*
X463079Y-326190D01*
X463862Y-326400D01*
X464645Y-326190D01*
X465272Y-325560D01*
X465585Y-324615D01*
Y-320100D01*
G01X471729Y-326400D02*
X468595D01*
Y-320100D01*
X471729D01*
G01X470475Y-323145D02*
X468595D01*
G01X475522Y-320100D02*
X477402D01*
G01X476462D02*
Y-326400D01*
G01X475522D02*
X477402D01*
G01X487417Y-325560D02*
X488044Y-326085D01*
X488749Y-326400D01*
X489375D01*
X490002Y-326085D01*
X490472Y-325560D01*
X490707Y-324825D01*
X490550Y-324090D01*
X490159Y-323460D01*
X489454Y-323040D01*
X488514Y-322830D01*
X487965Y-322410D01*
X487730Y-321675D01*
X487887Y-320940D01*
X488279Y-320415D01*
X488827Y-320100D01*
X489375D01*
X489924Y-320310D01*
X490394Y-320835D01*
G01X493717Y-326400D02*
Y-320100D01*
G01X497007D02*
Y-326400D01*
G01Y-323250D02*
X493717D01*
G01X499704Y-326400D02*
X501662Y-320100D01*
X503620Y-326400D01*
G01X502915Y-324195D02*
X500409D01*
G01X506160Y-326400D02*
Y-320100D01*
X509764Y-326400D01*
Y-320100D01*
G01X518917Y-326400D02*
Y-320100D01*
G01X522207D02*
Y-326400D01*
G01Y-323250D02*
X518917D01*
G01X525217Y-325560D02*
X525844Y-326085D01*
X526549Y-326400D01*
X527175D01*
X527802Y-326085D01*
X528272Y-325560D01*
X528507Y-324825D01*
X528350Y-324090D01*
X527959Y-323460D01*
X527254Y-323040D01*
X526314Y-322830D01*
X525765Y-322410D01*
X525530Y-321675D01*
X525687Y-320940D01*
X526079Y-320415D01*
X526627Y-320100D01*
X527175D01*
X527724Y-320310D01*
X528194Y-320835D01*
G01X532222Y-320100D02*
X534102D01*
G01X533162D02*
Y-326400D01*
G01X532222D02*
X534102D01*
G01X537504D02*
X539462Y-320100D01*
X541420Y-326400D01*
G01X540715Y-324195D02*
X538209D01*
G01X543960Y-326400D02*
Y-320100D01*
X547564Y-326400D01*
Y-320100D01*
G01X552532Y-323250D02*
X554099D01*
Y-325140D01*
X553629Y-325770D01*
X553080Y-326190D01*
X552297Y-326400D01*
X551514Y-326190D01*
X550965Y-325770D01*
X550495Y-325140D01*
X550182Y-324405D01*
X550025Y-323565D01*
Y-322830D01*
X550182Y-322200D01*
X550495Y-321465D01*
X550965Y-320835D01*
X551435Y-320415D01*
X552062Y-320100D01*
X552610D01*
X553237Y-320310D01*
X553707Y-320730D01*
G01X558205Y-327555D02*
X558519Y-326190D01*
G01X564662Y-320100D02*
Y-326400D01*
G01X562860Y-320100D02*
X566464D01*
G01X569004Y-326400D02*
X570962Y-320100D01*
X572920Y-326400D01*
G01X572215Y-324195D02*
X569709D01*
G01X577262Y-326400D02*
X576635Y-326295D01*
X576087Y-325875D01*
X575617Y-325245D01*
X575304Y-324510D01*
X575147Y-323670D01*
Y-322830D01*
X575304Y-321990D01*
X575617Y-321255D01*
X576087Y-320625D01*
X576635Y-320205D01*
X577262Y-320100D01*
X577889Y-320205D01*
X578437Y-320625D01*
X578907Y-321255D01*
X579220Y-321990D01*
X579377Y-322830D01*
Y-323670D01*
X579220Y-324510D01*
X578907Y-325245D01*
X578437Y-325875D01*
X577889Y-326295D01*
X577262Y-326400D01*
G01X589862D02*
Y-323565D01*
X588295Y-320100D01*
G01X591429D02*
X589862Y-323565D01*
G01X594439Y-320100D02*
Y-324615D01*
X594752Y-325560D01*
X595379Y-326190D01*
X596162Y-326400D01*
X596945Y-326190D01*
X597572Y-325560D01*
X597885Y-324615D01*
Y-320100D01*
G01X600504Y-326400D02*
X602462Y-320100D01*
X604420Y-326400D01*
G01X603715Y-324195D02*
X601209D01*
G01X606960Y-326400D02*
Y-320100D01*
X610564Y-326400D01*
Y-320100D01*
G01X455760Y-316400D02*
Y-310100D01*
X459364Y-316400D01*
Y-310100D01*
G01X463862Y-316400D02*
X463235Y-316295D01*
X462687Y-315875D01*
X462217Y-315245D01*
X461904Y-314510D01*
X461747Y-313670D01*
Y-312830D01*
X461904Y-311990D01*
X462217Y-311255D01*
X462687Y-310625D01*
X463235Y-310205D01*
X463862Y-310100D01*
X464489Y-310205D01*
X465037Y-310625D01*
X465507Y-311255D01*
X465820Y-311990D01*
X465977Y-312830D01*
Y-313670D01*
X465820Y-314510D01*
X465507Y-315245D01*
X465037Y-315875D01*
X464489Y-316295D01*
X463862Y-316400D01*
G01X470162Y-316610D02*
X470005Y-316505D01*
Y-316295D01*
X470162Y-316190D01*
X470319Y-316295D01*
Y-316505D01*
X470162Y-316610D01*
G01X476462Y-316400D02*
Y-310100D01*
X475522Y-311360D01*
G01Y-316400D02*
X477402D01*
G01X482762D02*
X483310Y-316295D01*
X483937Y-315980D01*
X484329Y-315455D01*
X484485Y-314720D01*
X484329Y-313985D01*
X483859Y-313355D01*
X483154Y-313040D01*
X482370D01*
X481900Y-312830D01*
X481509Y-312305D01*
X481352Y-311570D01*
X481587Y-310835D01*
X482135Y-310310D01*
X482762Y-310100D01*
X483389Y-310310D01*
X483937Y-310835D01*
X484172Y-311570D01*
X484015Y-312305D01*
X483624Y-312830D01*
X483154Y-313040D01*
X482370D01*
X481665Y-313355D01*
X481195Y-313985D01*
X481039Y-314720D01*
X481195Y-315455D01*
X481587Y-315980D01*
X482214Y-316295D01*
X482762Y-316400D01*
G01X489062D02*
X489610Y-316295D01*
X490237Y-315980D01*
X490629Y-315455D01*
X490785Y-314720D01*
X490629Y-313985D01*
X490159Y-313355D01*
X489454Y-313040D01*
X488670D01*
X488200Y-312830D01*
X487809Y-312305D01*
X487652Y-311570D01*
X487887Y-310835D01*
X488435Y-310310D01*
X489062Y-310100D01*
X489689Y-310310D01*
X490237Y-310835D01*
X490472Y-311570D01*
X490315Y-312305D01*
X489924Y-312830D01*
X489454Y-313040D01*
X488670D01*
X487965Y-313355D01*
X487495Y-313985D01*
X487339Y-314720D01*
X487495Y-315455D01*
X487887Y-315980D01*
X488514Y-316295D01*
X489062Y-316400D01*
G01X495205Y-317555D02*
X495519Y-316190D01*
G01X499312Y-310100D02*
X500409Y-316400D01*
X501662Y-310100D01*
X502915Y-316400D01*
X504012Y-310100D01*
G01X509529Y-316400D02*
X506395D01*
Y-310100D01*
X509529D01*
G01X508275Y-313145D02*
X506395D01*
G01X512460Y-316400D02*
Y-310100D01*
X516064Y-316400D01*
Y-310100D01*
G01X525217Y-316400D02*
Y-310100D01*
G01X528507D02*
Y-316400D01*
G01Y-313250D02*
X525217D01*
G01X530812Y-310100D02*
X531909Y-316400D01*
X533162Y-310100D01*
X534415Y-316400D01*
X535512Y-310100D01*
G01X537504Y-316400D02*
X539462Y-310100D01*
X541420Y-316400D01*
G01X540715Y-314195D02*
X538209D01*
G01X550574Y-311150D02*
X551044Y-310520D01*
X551592Y-310205D01*
X552219Y-310100D01*
X553002Y-310310D01*
X553550Y-310835D01*
X553707Y-311465D01*
X553629Y-312095D01*
X553315Y-312620D01*
X551749Y-313670D01*
X551044Y-314405D01*
X550574Y-315455D01*
X550417Y-316400D01*
X553707D01*
G01X556560D02*
Y-310100D01*
X560164Y-316400D01*
Y-310100D01*
G01X562939Y-316400D02*
Y-310100D01*
X564505D01*
X565132Y-310415D01*
X565602Y-310835D01*
X565994Y-311465D01*
X566307Y-312200D01*
X566385Y-313250D01*
X566307Y-314300D01*
X565994Y-315035D01*
X565602Y-315665D01*
X565132Y-316085D01*
X564505Y-316400D01*
X562939D01*
G01X575695D02*
Y-310100D01*
X577654D01*
X578280Y-310415D01*
X578672Y-310835D01*
X578829Y-311675D01*
X578672Y-312515D01*
X578202Y-313040D01*
X577654Y-313355D01*
X575695D01*
G01X577654D02*
X578829Y-316400D01*
G01X581839D02*
Y-310100D01*
X583405D01*
X584032Y-310415D01*
X584502Y-310835D01*
X584894Y-311465D01*
X585207Y-312200D01*
X585285Y-313250D01*
X585207Y-314300D01*
X584894Y-315035D01*
X584502Y-315665D01*
X584032Y-316085D01*
X583405Y-316400D01*
X581839D01*
G01X589862Y-316610D02*
X589705Y-316505D01*
Y-316295D01*
X589862Y-316190D01*
X590019Y-316295D01*
Y-316505D01*
X589862Y-316610D01*
G01X479862Y-303700D02*
X477342Y-303283D01*
X475137Y-301617D01*
X473247Y-299117D01*
X471987Y-296200D01*
X471357Y-292867D01*
Y-289533D01*
X471987Y-286200D01*
X473247Y-283283D01*
X475137Y-280784D01*
X477342Y-279117D01*
X479862Y-278700D01*
X482382Y-279117D01*
X484587Y-280784D01*
X486477Y-283283D01*
X487737Y-286200D01*
X488367Y-289533D01*
Y-292867D01*
X487737Y-296200D01*
X486477Y-299117D01*
X484587Y-301617D01*
X482382Y-303283D01*
X479862Y-303700D01*
G01X482382Y-297033D02*
X486162Y-303700D01*
G01X499707Y-287034D02*
Y-298700D01*
X500967Y-301617D01*
X502857Y-303283D01*
X505062Y-303700D01*
X507267Y-303283D01*
X509157Y-301617D01*
X510417Y-298700D01*
G01Y-303700D02*
Y-287034D01*
G01X535932Y-303700D02*
Y-287034D01*
G01Y-289950D02*
X534672Y-288284D01*
X532782Y-287450D01*
X530577Y-287034D01*
X528372Y-287867D01*
X526482Y-289533D01*
X525222Y-292034D01*
X524592Y-295367D01*
X525222Y-298700D01*
X526482Y-301201D01*
X528372Y-302867D01*
X530577Y-303700D01*
X532782Y-303283D01*
X534672Y-302034D01*
X535932Y-300367D01*
G01X550107Y-303700D02*
Y-287034D01*
G01Y-291200D02*
X551367Y-289117D01*
X553257Y-287450D01*
X555777Y-287034D01*
X557982Y-287450D01*
X559872Y-289117D01*
X560817Y-292034D01*
Y-303700D01*
G01X580662Y-278700D02*
Y-303700D01*
G01X576252Y-287034D02*
X585072D01*
G01X611532Y-303700D02*
Y-287034D01*
G01Y-289950D02*
X610272Y-288284D01*
X608382Y-287450D01*
X606177Y-287034D01*
X603972Y-287867D01*
X602082Y-289533D01*
X600822Y-292034D01*
X600192Y-295367D01*
X600822Y-298700D01*
X602082Y-301201D01*
X603972Y-302867D01*
X606177Y-303700D01*
X608382Y-303283D01*
X610272Y-302034D01*
X611532Y-300367D01*
G01X651212Y-283400D02*
Y-291400D01*
X655212D01*
G01X663012D02*
Y-286067D01*
G01Y-287000D02*
X662612Y-286467D01*
X662012Y-286200D01*
X661312Y-286067D01*
X660612Y-286333D01*
X660012Y-286867D01*
X659612Y-287667D01*
X659412Y-288733D01*
X659612Y-289800D01*
X660012Y-290600D01*
X660612Y-291133D01*
X661312Y-291400D01*
X662012Y-291267D01*
X662612Y-290867D01*
X663012Y-290334D01*
G01X667112Y-293800D02*
X667712Y-294067D01*
X668512Y-293800D01*
X669012Y-293267D01*
X669412Y-292600D01*
X670012Y-290467D01*
X671312Y-286067D01*
G01X668112D02*
X670012Y-290467D01*
G01X675712Y-287800D02*
X678912D01*
X678612Y-286867D01*
X678112Y-286333D01*
X677412Y-286067D01*
X676712Y-286200D01*
X676112Y-286600D01*
X675712Y-287533D01*
X675512Y-288334D01*
Y-289133D01*
X675712Y-289933D01*
X676212Y-290733D01*
X676812Y-291267D01*
X677512Y-291400D01*
X678212Y-291133D01*
X678912Y-290334D01*
G01X683812Y-291400D02*
Y-286067D01*
G01Y-287133D02*
X684312Y-286600D01*
X684812Y-286200D01*
X685512Y-286067D01*
X686012Y-286200D01*
X686612Y-286600D01*
G01X673512Y-333400D02*
X675912D01*
G01X674712D02*
Y-341400D01*
G01X673512D02*
X675912D01*
G01X681312D02*
Y-336067D01*
G01Y-337133D02*
X681812Y-336600D01*
X682312Y-336200D01*
X683012Y-336067D01*
X683512Y-336200D01*
X684112Y-336600D01*
G01X689212Y-337800D02*
X692412D01*
X692112Y-336867D01*
X691612Y-336333D01*
X690912Y-336067D01*
X690212Y-336200D01*
X689612Y-336600D01*
X689212Y-337533D01*
X689012Y-338334D01*
Y-339133D01*
X689212Y-339933D01*
X689712Y-340733D01*
X690312Y-341267D01*
X691012Y-341400D01*
X691712Y-341133D01*
X692412Y-340334D01*
G01X697012Y-341400D02*
Y-336067D01*
G01Y-337400D02*
X697412Y-336733D01*
X698012Y-336200D01*
X698812Y-336067D01*
X699512Y-336200D01*
X700112Y-336733D01*
X700412Y-337667D01*
Y-341400D01*
G01X705212Y-337800D02*
X708412D01*
X708112Y-336867D01*
X707612Y-336333D01*
X706912Y-336067D01*
X706212Y-336200D01*
X705612Y-336600D01*
X705212Y-337533D01*
X705012Y-338334D01*
Y-339133D01*
X705212Y-339933D01*
X705712Y-340733D01*
X706312Y-341267D01*
X707012Y-341400D01*
X707712Y-341133D01*
X708412Y-340334D01*
G01X662712Y-316400D02*
Y-308400D01*
X665112D01*
X665912Y-308800D01*
X666512Y-309733D01*
X666712Y-310800D01*
X666512Y-311867D01*
X666012Y-312667D01*
X665112Y-313067D01*
X662712D01*
G01X670212Y-316400D02*
X672712Y-308400D01*
X675212Y-316400D01*
G01X674312Y-313600D02*
X671112D01*
G01X678612Y-315334D02*
X679412Y-316000D01*
X680312Y-316400D01*
X681112D01*
X681912Y-316000D01*
X682512Y-315334D01*
X682812Y-314400D01*
X682612Y-313467D01*
X682112Y-312667D01*
X681212Y-312133D01*
X680012Y-311867D01*
X679312Y-311333D01*
X679012Y-310400D01*
X679212Y-309467D01*
X679712Y-308800D01*
X680412Y-308400D01*
X681112D01*
X681812Y-308667D01*
X682412Y-309333D01*
G01X688712Y-308400D02*
Y-316400D01*
G01X686412Y-308400D02*
X691012D01*
G01X695412Y-313733D02*
X698012D01*
G01X705512Y-312133D02*
X705912Y-311733D01*
X706212Y-311067D01*
X706412Y-310133D01*
X706212Y-309333D01*
X705812Y-308800D01*
X705112Y-308400D01*
X702412D01*
Y-316400D01*
X705712D01*
X706412Y-315867D01*
X706812Y-315067D01*
X707012Y-314133D01*
X706812Y-313200D01*
X706212Y-312400D01*
X705512Y-312133D01*
X702412D01*
G01X712712Y-316400D02*
X711912Y-316267D01*
X711212Y-315733D01*
X710612Y-314933D01*
X710212Y-314000D01*
X710012Y-312933D01*
Y-311867D01*
X710212Y-310800D01*
X710612Y-309867D01*
X711212Y-309067D01*
X711912Y-308533D01*
X712712Y-308400D01*
X713512Y-308533D01*
X714212Y-309067D01*
X714812Y-309867D01*
X715212Y-310800D01*
X715412Y-311867D01*
Y-312933D01*
X715212Y-314000D01*
X714812Y-314933D01*
X714212Y-315733D01*
X713512Y-316267D01*
X712712Y-316400D01*
G01X720712Y-308400D02*
Y-316400D01*
G01X718412Y-308400D02*
X723012D01*
G01X777812Y-334733D02*
X778412Y-333933D01*
X779112Y-333533D01*
X779912Y-333400D01*
X780912Y-333667D01*
X781612Y-334333D01*
X781812Y-335133D01*
X781712Y-335934D01*
X781312Y-336600D01*
X779312Y-337933D01*
X778412Y-338867D01*
X777812Y-340200D01*
X777612Y-341400D01*
X781812D01*
G01X787712Y-333400D02*
X786912Y-333667D01*
X786312Y-334333D01*
X785912Y-335133D01*
X785612Y-336200D01*
X785512Y-337400D01*
X785612Y-338600D01*
X785912Y-339667D01*
X786312Y-340467D01*
X786912Y-341133D01*
X787712Y-341400D01*
X788512Y-341133D01*
X789112Y-340467D01*
X789512Y-339667D01*
X789812Y-338600D01*
X789912Y-337400D01*
X789812Y-336200D01*
X789512Y-335133D01*
X789112Y-334333D01*
X788512Y-333667D01*
X787712Y-333400D01*
G01X795712Y-341400D02*
Y-333400D01*
X794512Y-335000D01*
G01Y-341400D02*
X796912D01*
G01X801812Y-334733D02*
X802412Y-333933D01*
X803112Y-333533D01*
X803912Y-333400D01*
X804912Y-333667D01*
X805612Y-334333D01*
X805812Y-335133D01*
X805712Y-335934D01*
X805312Y-336600D01*
X803312Y-337933D01*
X802412Y-338867D01*
X801812Y-340200D01*
X801612Y-341400D01*
X805812D01*
G01X809912Y-341667D02*
X813512Y-333400D01*
G01X819712Y-341400D02*
Y-333400D01*
X818512Y-335000D01*
G01Y-341400D02*
X820912D01*
G01X827712Y-333400D02*
X826912Y-333667D01*
X826312Y-334333D01*
X825912Y-335133D01*
X825612Y-336200D01*
X825512Y-337400D01*
X825612Y-338600D01*
X825912Y-339667D01*
X826312Y-340467D01*
X826912Y-341133D01*
X827712Y-341400D01*
X828512Y-341133D01*
X829112Y-340467D01*
X829512Y-339667D01*
X829812Y-338600D01*
X829912Y-337400D01*
X829812Y-336200D01*
X829512Y-335133D01*
X829112Y-334333D01*
X828512Y-333667D01*
X827712Y-333400D01*
G01X833912Y-341667D02*
X837512Y-333400D01*
G01X841512Y-339800D02*
X842112Y-340733D01*
X842912Y-341267D01*
X843812Y-341400D01*
X844612Y-341267D01*
X845412Y-340600D01*
X845912Y-339800D01*
X846012Y-339000D01*
X845812Y-338067D01*
X845112Y-337400D01*
X844412Y-337133D01*
X843512D01*
G01X844412D02*
X845012Y-336733D01*
X845512Y-336067D01*
X845712Y-335267D01*
X845512Y-334467D01*
X845012Y-333800D01*
X844112Y-333400D01*
X843212Y-333533D01*
X842312Y-334067D01*
G01X851712Y-341400D02*
Y-333400D01*
X850512Y-335000D01*
G01Y-341400D02*
X852912D01*
G01X777512Y-316400D02*
Y-308400D01*
X779512D01*
X780312Y-308800D01*
X780912Y-309333D01*
X781412Y-310133D01*
X781812Y-311067D01*
X781912Y-312400D01*
X781812Y-313733D01*
X781412Y-314667D01*
X780912Y-315467D01*
X780312Y-316000D01*
X779512Y-316400D01*
X777512D01*
G01X785212D02*
X787712Y-308400D01*
X790212Y-316400D01*
G01X789312Y-313600D02*
X786112D01*
G01X795712Y-308400D02*
X794912Y-308667D01*
X794312Y-309333D01*
X793912Y-310133D01*
X793612Y-311200D01*
X793512Y-312400D01*
X793612Y-313600D01*
X793912Y-314667D01*
X794312Y-315467D01*
X794912Y-316133D01*
X795712Y-316400D01*
X796512Y-316133D01*
X797112Y-315467D01*
X797512Y-314667D01*
X797812Y-313600D01*
X797912Y-312400D01*
X797812Y-311200D01*
X797512Y-310133D01*
X797112Y-309333D01*
X796512Y-308667D01*
X795712Y-308400D01*
G01X803712D02*
Y-316400D01*
G01X801412Y-308400D02*
X806012D01*
G01X809812Y-313067D02*
X810512Y-312133D01*
X811112Y-311600D01*
X811912Y-311333D01*
X812612Y-311600D01*
X813112Y-312133D01*
X813512Y-312933D01*
X813612Y-313867D01*
X813512Y-314667D01*
X813112Y-315467D01*
X812512Y-316133D01*
X811812Y-316400D01*
X811012Y-316133D01*
X810312Y-315334D01*
X809912Y-314133D01*
X809812Y-312800D01*
X810012Y-311067D01*
X810312Y-310133D01*
X810812Y-309200D01*
X811512Y-308533D01*
X812212Y-308400D01*
X812912Y-308667D01*
X813412Y-309333D01*
G01X817112Y-316400D02*
Y-308400D01*
X819712Y-315067D01*
X822312Y-308400D01*
Y-316400D01*
G01X827712Y-308400D02*
Y-316400D01*
G01X825412Y-308400D02*
X830012D01*
G01X833612Y-316400D02*
Y-308400D01*
G01X837812D02*
Y-316400D01*
G01Y-312400D02*
X833612D01*
G01X843712Y-316400D02*
X844412Y-316267D01*
X845212Y-315867D01*
X845712Y-315200D01*
X845912Y-314267D01*
X845712Y-313334D01*
X845112Y-312533D01*
X844212Y-312133D01*
X843212D01*
X842612Y-311867D01*
X842112Y-311200D01*
X841912Y-310267D01*
X842212Y-309333D01*
X842912Y-308667D01*
X843712Y-308400D01*
X844512Y-308667D01*
X845212Y-309333D01*
X845512Y-310267D01*
X845312Y-311200D01*
X844812Y-311867D01*
X844212Y-312133D01*
X843212D01*
X842312Y-312533D01*
X841712Y-313334D01*
X841512Y-314267D01*
X841712Y-315200D01*
X842212Y-315867D01*
X843012Y-316267D01*
X843712Y-316400D01*
G01X853912Y-309067D02*
X853312Y-308667D01*
X852612Y-308400D01*
X851812D01*
X850912Y-308800D01*
X850212Y-309467D01*
X849712Y-310267D01*
X849312Y-311600D01*
X849212Y-312800D01*
X849412Y-314000D01*
X849712Y-314800D01*
X850312Y-315600D01*
X851012Y-316133D01*
X851712Y-316400D01*
X852412D01*
X853112Y-316133D01*
X853712Y-315733D01*
X854212Y-315200D01*
G01X859712Y-308400D02*
X858912Y-308667D01*
X858312Y-309333D01*
X857912Y-310133D01*
X857612Y-311200D01*
X857512Y-312400D01*
X857612Y-313600D01*
X857912Y-314667D01*
X858312Y-315467D01*
X858912Y-316133D01*
X859712Y-316400D01*
X860512Y-316133D01*
X861112Y-315467D01*
X861512Y-314667D01*
X861812Y-313600D01*
X861912Y-312400D01*
X861812Y-311200D01*
X861512Y-310133D01*
X861112Y-309333D01*
X860512Y-308667D01*
X859712Y-308400D01*
G01X799712Y-283400D02*
Y-291400D01*
G01X797412Y-283400D02*
X802012D01*
G01X805812Y-288067D02*
X806512Y-287133D01*
X807112Y-286600D01*
X807912Y-286333D01*
X808612Y-286600D01*
X809112Y-287133D01*
X809512Y-287933D01*
X809612Y-288867D01*
X809512Y-289667D01*
X809112Y-290467D01*
X808512Y-291133D01*
X807812Y-291400D01*
X807012Y-291133D01*
X806312Y-290334D01*
X805912Y-289133D01*
X805812Y-287800D01*
X806012Y-286067D01*
X806312Y-285133D01*
X806812Y-284200D01*
X807512Y-283533D01*
X808212Y-283400D01*
X808912Y-283667D01*
X809412Y-284333D01*
G01X813112Y-291400D02*
Y-283400D01*
X815712Y-290067D01*
X818312Y-283400D01*
Y-291400D01*
G01X820712Y-294067D02*
X826712D01*
G01X831712Y-283400D02*
Y-291400D01*
G01X829412Y-283400D02*
X834012D01*
G01X838312Y-291400D02*
Y-286067D01*
G01Y-287133D02*
X838812Y-286600D01*
X839312Y-286200D01*
X840012Y-286067D01*
X840512Y-286200D01*
X841112Y-286600D01*
G01X849512Y-291400D02*
Y-286067D01*
G01Y-287000D02*
X849112Y-286467D01*
X848512Y-286200D01*
X847812Y-286067D01*
X847112Y-286333D01*
X846512Y-286867D01*
X846112Y-287667D01*
X845912Y-288733D01*
X846112Y-289800D01*
X846512Y-290600D01*
X847112Y-291133D01*
X847812Y-291400D01*
X848512Y-291267D01*
X849112Y-290867D01*
X849512Y-290334D01*
G01X853612Y-293800D02*
X854212Y-294067D01*
X855012Y-293800D01*
X855512Y-293267D01*
X855912Y-292600D01*
X856512Y-290467D01*
X857812Y-286067D01*
G01X854612D02*
X856512Y-290467D01*
G01X860712Y-294067D02*
X866712D01*
G01X872512Y-287133D02*
X872912Y-286733D01*
X873212Y-286067D01*
X873412Y-285133D01*
X873212Y-284333D01*
X872812Y-283800D01*
X872112Y-283400D01*
X869412D01*
Y-291400D01*
X872712D01*
X873412Y-290867D01*
X873812Y-290067D01*
X874012Y-289133D01*
X873812Y-288200D01*
X873212Y-287400D01*
X872512Y-287133D01*
X869412D01*
G01X877712Y-291400D02*
Y-283400D01*
X880112D01*
X880912Y-283800D01*
X881512Y-284733D01*
X881712Y-285800D01*
X881512Y-286867D01*
X881012Y-287667D01*
X880112Y-288067D01*
X877712D01*
G01X896912Y-334067D02*
X896312Y-333667D01*
X895612Y-333400D01*
X894812D01*
X893912Y-333800D01*
X893212Y-334467D01*
X892712Y-335267D01*
X892312Y-336600D01*
X892212Y-337800D01*
X892412Y-339000D01*
X892712Y-339800D01*
X893312Y-340600D01*
X894012Y-341133D01*
X894712Y-341400D01*
X895412D01*
X896112Y-341133D01*
X896712Y-340733D01*
X897212Y-340200D01*
G01X922212Y-341400D02*
Y-333400D01*
X921012Y-335000D01*
G01Y-341400D02*
X923412D01*
G01X928312Y-338067D02*
X929012Y-337133D01*
X929612Y-336600D01*
X930412Y-336333D01*
X931112Y-336600D01*
X931612Y-337133D01*
X932012Y-337933D01*
X932112Y-338867D01*
X932012Y-339667D01*
X931612Y-340467D01*
X931012Y-341133D01*
X930312Y-341400D01*
X929512Y-341133D01*
X928812Y-340334D01*
X928412Y-339133D01*
X928312Y-337800D01*
X928512Y-336067D01*
X928812Y-335133D01*
X929312Y-334200D01*
X930012Y-333533D01*
X930712Y-333400D01*
X931412Y-333667D01*
X931912Y-334333D01*
G54D12*
X44528Y41339D03*
Y53150D03*
X56339Y41339D03*
Y53150D03*
X44528Y64961D03*
Y76772D03*
X56339Y64961D03*
Y76772D03*
X44528Y88583D03*
Y100394D03*
X56339Y88583D03*
Y100394D03*
X44528Y112205D03*
Y124016D03*
X56339Y112205D03*
Y124016D03*
X44528Y135827D03*
G54D13*
X56339D03*
G54D14*
X68400Y141200D03*
X64500Y165200D03*
X99100Y127470D03*
X89400Y165300D03*
X102400Y59600D03*
X111958Y73600D03*
X121958Y70900D03*
X116958Y68600D03*
X106958Y68500D03*
X102590Y115680D03*
X115400Y120270D03*
X107390Y125110D03*
X119800Y124390D03*
X108900Y137300D03*
X114300Y134900D03*
X119700Y132400D03*
X111500Y129900D03*
X105800Y165400D03*
X128600Y114510D03*
X132500Y110100D03*
X125000Y126400D03*
X141400Y164800D03*
X129000D03*
X169200Y165200D03*
X155500Y164800D03*
X183300Y164700D03*
X346800Y113500D03*
X345400Y107600D03*
X346200Y102500D03*
X350700Y121642D03*
X345900Y125100D03*
X347350Y143750D03*
X346906Y137693D03*
X362500Y97100D03*
X357800Y114657D03*
X357600Y108561D03*
X356861Y102961D03*
X414900Y6500D03*
X463435Y79865D03*
X453900Y92300D03*
X453300Y86800D03*
X451100Y81400D03*
X452100Y97000D03*
X452000Y102200D03*
X488000Y89800D03*
X477630Y88900D03*
X525700Y99300D03*
X519400Y96400D03*
X520439Y91000D03*
X516500Y87442D03*
X571500Y7500D03*
X604200Y107400D03*
X614900Y90157D03*
X615600Y95139D03*
X625600Y95400D03*
X625700Y90100D03*
X615500Y100157D03*
X622658Y112158D03*
X622200Y120258D03*
X615500Y105157D03*
X626173Y148400D03*
X617949Y147000D03*
X659310Y72900D03*
X664310D03*
X654400Y92100D03*
Y97100D03*
X672638Y93290D03*
X666614Y121000D03*
X661614D03*
X671063Y125930D03*
X676063D03*
X680300Y75600D03*
X689723Y89400D03*
X689311Y96311D03*
X677638Y93290D03*
X689961Y122030D03*
X694961D03*
X680612Y129600D03*
X685612D03*
X701100Y16900D03*
X701670Y97100D03*
Y92100D03*
X740300Y87300D03*
X735807Y96593D03*
X724400Y105600D03*
X729400D03*
X730310Y115390D03*
X725310D03*
X761929Y72900D03*
X756929D03*
X752480Y92830D03*
X747480D03*
X764153Y96153D03*
X745905Y120452D03*
X750905D03*
X764803Y120330D03*
X760410Y124730D03*
X755410D03*
X778200Y92130D03*
Y97130D03*
X776032Y101968D03*
X769803Y120330D03*
X1223200Y99000D03*
X1216500Y119500D03*
X1216700Y114400D03*
X1216500Y108300D03*
X1216400Y102600D03*
X1226900Y119561D03*
Y114043D03*
X1227000Y108361D03*
X1227100Y102861D03*
X1219600Y129400D03*
X1219400Y123900D03*
X1211200Y144900D03*
X1217405Y143895D03*
X1229800Y96400D03*
X1238100Y127900D03*
X1323000Y99239D03*
X1321400Y92800D03*
X1321500Y82600D03*
X1322500Y87800D03*
X1359000Y91000D03*
X1387400Y87242D03*
X1389900Y97600D03*
X1395200Y99500D03*
X1391000Y92400D03*
X1442400Y8200D03*
X1494200Y97800D03*
X1495000Y92800D03*
X1484700Y93057D03*
X1485000Y98057D03*
X1484900Y103257D03*
X1492300Y117558D03*
X1484800Y109357D03*
X1492042Y126358D03*
X1495800Y147800D03*
X1487600Y147000D03*
X1524478Y97100D03*
Y92100D03*
X1534388Y72900D03*
X1529388D03*
X1550500Y75500D03*
X1542716Y93290D03*
X1547716D03*
X1531692Y121000D03*
X1536692D03*
X1546141Y125930D03*
X1550690Y129600D03*
X1541141Y125930D03*
X1570800Y18900D03*
X1571748Y92100D03*
Y97100D03*
X1559802Y89400D03*
X1559389Y96311D03*
X1565039Y122030D03*
X1560039D03*
X1555690Y129600D03*
X1594478Y105600D03*
X1595388Y115390D03*
X1617558Y92830D03*
X1610379Y87300D03*
X1605885Y96593D03*
X1599478Y105600D03*
X1600388Y115390D03*
X1615983Y120452D03*
X1627007Y72900D03*
X1632007D03*
X1622558Y92830D03*
X1634231Y96153D03*
X1620983Y120452D03*
X1639881Y120330D03*
X1634881D03*
X1625488Y124730D03*
X1630488D03*
X1648278Y97130D03*
Y92130D03*
X1646110Y101968D03*
G54D15*
X81929Y76772D03*
Y68898D03*
X89803Y76772D03*
Y68898D03*
X81929Y100394D03*
Y92520D03*
Y84646D03*
X89803Y100394D03*
Y92520D03*
Y84646D03*
X81929Y108268D03*
X89803D03*
G54D16*
X109500Y41000D03*
X1009800Y81300D03*
X1636400Y43100D03*
G54D17*
X468859Y115666D03*
Y141650D03*
X488859Y115666D03*
X478859D03*
X483859Y125666D03*
X473859D03*
X478859Y141650D03*
X488859D03*
X473859Y151650D03*
X483859D03*
X498859Y115666D03*
X503859Y125666D03*
X493859D03*
X498859Y141650D03*
X493859Y151650D03*
X1338938Y115666D03*
X1343938Y125666D03*
X1338938Y141650D03*
X1343938Y151650D03*
X1358938Y115666D03*
X1348938D03*
X1363938Y125666D03*
X1353938D03*
X1348938Y141650D03*
X1358938D03*
X1353938Y151650D03*
X1363938D03*
X1368938Y115666D03*
X1373938Y125666D03*
X1368938Y141650D03*
G54D18*
X452875Y131650D03*
X455867Y153658D03*
X452875Y194642D03*
X516851Y140666D03*
X519843Y115666D03*
Y194642D03*
X1322954Y131650D03*
Y194642D03*
X1325946Y153658D03*
X1389922Y115666D03*
X1386930Y140666D03*
X1389922Y194642D03*
G54D19*
X503859Y151650D03*
X1373938D03*
M02*
